(kicad_pcb
	(version 20260206)
	(generator "pcbnew")
	(generator_version "10.0")
	(general
		(thickness 1.6)
		(legacy_teardrops no)
	)
	(paper "A4")
	(title_block
		(title "12092022_DA0F0TYB4D0_F0T_Panel_BD_Front_D_brd_v02_OCP.brd")
		(comment 1 "Grand Teton / footprints 70-72 of 128")
	)
	(layers
		(0 "F.Cu" signal "TOP")
		(4 "In1.Cu" signal "GND")
		(6 "In2.Cu" signal "GND1")
		(2 "B.Cu" signal "BOTTOM")
		(9 "F.Adhes" user "F.Adhesive")
		(11 "B.Adhes" user "B.Adhesive")
		(13 "F.Paste" user "Package Geometry/Pastemask Top")
		(15 "B.Paste" user "Package Geometry/Pastemask Bottom")
		(5 "F.SilkS" user "Ref Des/Silkscreen Top")
		(7 "B.SilkS" user "Ref Des/Silkscreen Bottom")
		(1 "F.Mask" user "Board Geometry/Soldermask Top")
		(3 "B.Mask" user "Board Geometry/Soldermask Bottom")
		(17 "Dwgs.User" user "User.Drawings")
		(19 "Cmts.User" user "User.Comments")
		(21 "Eco1.User" user "User.Eco1")
		(23 "Eco2.User" user "User.Eco2")
		(25 "Edge.Cuts" user "Board Geometry/Outline")
		(27 "Margin" user)
		(31 "F.CrtYd" user "Package Geometry/Place Bound Top")
		(29 "B.CrtYd" user "Package Geometry/Place Bound Bottom")
		(35 "F.Fab" user "Ref Des/Assembly Top")
		(33 "B.Fab" user "Ref Des/Assembly Bottom")
	)
	(footprint ""
		(layer "F.Cu")
		(at 3.048 -25.273 180)
		(property "Reference" "R8"
			(at 1.905 -0.02667 0)
			(unlocked yes)
			(layer "F.SilkS")
			(effects
				(font
					(size 0.7874 0.5842)
					(thickness 0.1524)
				)
			)
		)
		(property "Value" ""
			(at 0 0 180)
			(layer "F.Fab")
			(effects
				(font
					(size 1.27 1.27)
				)
			)
		)
		(duplicate_pad_numbers_are_jumpers no)
		(fp_line
			(start 0.7874 0.4064)
			(end -0.7874 0.4064)
			(stroke
				(width 0.1524)
				(type default)
			)
			(layer "F.SilkS")
		)
		(fp_line
			(start 0.7874 -0.4064)
			(end 0.7874 0.4064)
			(stroke
				(width 0.1524)
				(type default)
			)
			(layer "F.SilkS")
		)
		(fp_line
			(start -0.7874 0.4064)
			(end -0.7874 -0.4064)
			(stroke
				(width 0.1524)
				(type default)
			)
			(layer "F.SilkS")
		)
		(fp_line
			(start -0.7874 -0.4064)
			(end 0.7874 -0.4064)
			(stroke
				(width 0.1524)
				(type default)
			)
			(layer "F.SilkS")
		)
		(fp_line
			(start 0.67945 0.3048)
			(end 0.120396 0.3048)
			(stroke
				(width 0.1)
				(type default)
			)
			(layer "F.Fab")
		)
		(fp_line
			(start 0.67945 -0.3048)
			(end 0.67945 0.3048)
			(stroke
				(width 0.1)
				(type default)
			)
			(layer "F.Fab")
		)
		(fp_line
			(start 0.12065 -0.2794)
			(end 0.12065 -0.3048)
			(stroke
				(width 0.1)
				(type default)
			)
			(layer "F.Fab")
		)
		(fp_line
			(start 0.12065 -0.3048)
			(end 0.67945 -0.3048)
			(stroke
				(width 0.1)
				(type default)
			)
			(layer "F.Fab")
		)
		(fp_line
			(start 0.120396 0.3048)
			(end 0.120396 0.2794)
			(stroke
				(width 0.1)
				(type default)
			)
			(layer "F.Fab")
		)
		(fp_line
			(start 0.120396 0.2794)
			(end -0.12065 0.2794)
			(stroke
				(width 0.1)
				(type default)
			)
			(layer "F.Fab")
		)
		(fp_line
			(start -0.12065 0.3048)
			(end -0.67945 0.3048)
			(stroke
				(width 0.1)
				(type default)
			)
			(layer "F.Fab")
		)
		(fp_line
			(start -0.12065 0.2794)
			(end -0.12065 0.3048)
			(stroke
				(width 0.1)
				(type default)
			)
			(layer "F.Fab")
		)
		(fp_line
			(start -0.12065 -0.2794)
			(end 0.12065 -0.2794)
			(stroke
				(width 0.1)
				(type default)
			)
			(layer "F.Fab")
		)
		(fp_line
			(start -0.12065 -0.305054)
			(end -0.12065 -0.2794)
			(stroke
				(width 0.1)
				(type default)
			)
			(layer "F.Fab")
		)
		(fp_line
			(start -0.67945 0.3048)
			(end -0.67945 -0.305054)
			(stroke
				(width 0.1)
				(type default)
			)
			(layer "F.Fab")
		)
		(fp_line
			(start -0.67945 -0.305054)
			(end -0.12065 -0.305054)
			(stroke
				(width 0.1)
				(type default)
			)
			(layer "F.Fab")
		)
		(pad "1" smd circle
			(at -0.40005 0 180)
			(size 0 0)
			(layers "F.Cu" "F.Mask" "F.Paste")
			(net "SYSTEM_FAULT_ID_LED_R1")
		)
		(pad "2" smd circle
			(at 0.40005 0 180)
			(size 0 0)
			(layers "F.Cu" "F.Mask" "F.Paste")
			(net "GND")
		)
	)
	(footprint ""
		(layer "F.Cu")
		(at 21.850096 -77.250036 180)
		(property "Reference" "J1"
			(at 8.007096 -7.553706 0)
			(unlocked yes)
			(layer "F.SilkS")
			(effects
				(font
					(size 0.7874 0.5842)
					(thickness 0.1524)
				)
				(justify left)
			)
		)
		(property "Value" ""
			(at 0 0 180)
			(layer "F.Fab")
			(effects
				(font
					(size 1.27 1.27)
				)
			)
		)
		(duplicate_pad_numbers_are_jumpers no)
		(fp_line
			(start 6.35 7.899908)
			(end 6.35 6.400292)
			(stroke
				(width 0.1524)
				(type default)
			)
			(layer "F.SilkS")
		)
		(fp_line
			(start 6.35 3.400552)
			(end 6.35 5.099812)
			(stroke
				(width 0.1524)
				(type default)
			)
			(layer "F.SilkS")
		)
		(fp_line
			(start 6.35 -1.781048)
			(end 6.35 2.100072)
			(stroke
				(width 0.1524)
				(type default)
			)
			(layer "F.SilkS")
		)
		(fp_line
			(start 6.35 -7.899908)
			(end 6.35 -3.015488)
			(stroke
				(width 0.1524)
				(type default)
			)
			(layer "F.SilkS")
		)
		(fp_line
			(start 5.71754 -7.899908)
			(end 6.35 -7.899908)
			(stroke
				(width 0.1524)
				(type default)
			)
			(layer "F.SilkS")
		)
		(fp_line
			(start -6.35 7.899908)
			(end 6.35 7.899908)
			(stroke
				(width 0.1524)
				(type default)
			)
			(layer "F.SilkS")
		)
		(fp_line
			(start -6.35 6.400292)
			(end -6.35 7.899908)
			(stroke
				(width 0.1524)
				(type default)
			)
			(layer "F.SilkS")
		)
		(fp_line
			(start -6.35 5.099812)
			(end -6.35 3.400552)
			(stroke
				(width 0.1524)
				(type default)
			)
			(layer "F.SilkS")
		)
		(fp_line
			(start -6.35 2.100072)
			(end -6.35 -1.783588)
			(stroke
				(width 0.1524)
				(type default)
			)
			(layer "F.SilkS")
		)
		(fp_line
			(start -6.35 -3.015488)
			(end -6.35 -7.899908)
			(stroke
				(width 0.1524)
				(type default)
			)
			(layer "F.SilkS")
		)
		(fp_line
			(start -6.35 -7.899908)
			(end -5.71754 -7.899908)
			(stroke
				(width 0.1524)
				(type default)
			)
			(layer "F.SilkS")
		)
		(fp_poly
			(pts
				(xy -7.50824 -4.592066) (xy -7.50824 -5.608066) (xy -6.49224 -5.100066)
			)
			(stroke
				(width 0)
				(type default)
			)
			(fill yes)
			(layer "F.SilkS")
		)
		(fp_line
			(start 6.35 7.899908)
			(end -6.35 7.899908)
			(stroke
				(width 0.1)
				(type default)
			)
			(layer "F.Fab")
		)
		(fp_line
			(start 6.35 -7.899908)
			(end 6.35 7.899908)
			(stroke
				(width 0.1)
				(type default)
			)
			(layer "F.Fab")
		)
		(fp_line
			(start -6.35 7.899908)
			(end -6.35 -7.899908)
			(stroke
				(width 0.1)
				(type default)
			)
			(layer "F.Fab")
		)
		(fp_line
			(start -6.35 -7.899908)
			(end 6.35 -7.899908)
			(stroke
				(width 0.1)
				(type default)
			)
			(layer "F.Fab")
		)
		(fp_poly
			(pts
				(xy -7.50824 -4.592066) (xy -7.50824 -5.608066) (xy -6.49224 -5.100066)
			)
			(stroke
				(width 0)
				(type default)
			)
			(fill yes)
			(layer "F.Fab")
		)
		(pad "" np_thru_hole circle
			(at -5.5499 -2.400046)
			(size 1.3208 1.3208)
			(drill 1.3208)
			(layers "*.Cu" "*.Mask")
			(clearance 0.381)
			(thermal_gap 0.381)
		)
		(pad "" np_thru_hole circle
			(at 5.5499 -2.400046)
			(size 1.3208 1.3208)
			(drill 1.3208)
			(layers "*.Cu" "*.Mask")
			(clearance 0.381)
			(thermal_gap 0.381)
		)
		(pad "A1" smd rect
			(at -5.40004 -5.100066)
			(size 0.381 1.3462)
			(layers "F.Cu" "F.Mask" "F.Paste")
			(net "GND")
		)
		(pad "A2" smd rect
			(at -4.800092 -5.100066)
			(size 0.381 1.3462)
			(layers "F.Cu" "F.Mask" "F.Paste")
			(net "GND")
		)
		(pad "A3" smd rect
			(at -4.19989 -5.100066)
			(size 0.381 1.3462)
			(layers "F.Cu" "F.Mask" "F.Paste")
			(net "GND")
		)
		(pad "A4" smd rect
			(at -3.599942 -5.100066)
			(size 0.381 1.3462)
			(layers "F.Cu" "F.Mask" "F.Paste")
			(net "GND")
		)
		(pad "A5" smd rect
			(at -2.999994 -5.100066)
			(size 0.381 1.3462)
			(layers "F.Cu" "F.Mask" "F.Paste")
			(net "P5V_STBY")
		)
		(pad "A6" smd rect
			(at -2.400046 -5.100066)
			(size 0.381 1.3462)
			(layers "F.Cu" "F.Mask" "F.Paste")
			(net "P5V_STBY")
		)
		(pad "A7" smd rect
			(at -1.800098 -5.100066)
			(size 0.381 1.3462)
			(layers "F.Cu" "F.Mask" "F.Paste")
			(net "GND")
		)
		(pad "A8" smd rect
			(at -1.199896 -5.100066)
			(size 0.381 1.3462)
			(layers "F.Cu" "F.Mask" "F.Paste")
			(net "P5V_STBY")
		)
		(pad "A9" smd rect
			(at -0.599948 -5.100066)
			(size 0.381 1.3462)
			(layers "F.Cu" "F.Mask" "F.Paste")
			(net "P5V_STBY")
		)
		(pad "A10" smd rect
			(at 0 -5.100066)
			(size 0.381 1.3462)
			(layers "F.Cu" "F.Mask" "F.Paste")
			(net "GND")
		)
		(pad "A11" smd rect
			(at 0.599948 -5.100066)
			(size 0.381 1.3462)
			(layers "F.Cu" "F.Mask" "F.Paste")
			(net "GND")
		)
		(pad "A12" smd rect
			(at 1.199896 -5.100066)
			(size 0.381 1.3462)
			(layers "F.Cu" "F.Mask" "F.Paste")
			(net "GND")
		)
		(pad "A13" smd rect
			(at 1.800098 -5.100066)
			(size 0.381 1.3462)
			(layers "F.Cu" "F.Mask" "F.Paste")
			(net "GND")
		)
		(pad "A14" smd rect
			(at 2.400046 -5.100066)
			(size 0.381 1.3462)
			(layers "F.Cu" "F.Mask" "F.Paste")
			(net "P5V_STBY")
		)
		(pad "A15" smd rect
			(at 2.999994 -5.100066)
			(size 0.381 1.3462)
			(layers "F.Cu" "F.Mask" "F.Paste")
			(net "P5V_STBY")
		)
		(pad "A16" smd rect
			(at 3.599942 -5.100066)
			(size 0.381 1.3462)
			(layers "F.Cu" "F.Mask" "F.Paste")
			(net "GND")
		)
		(pad "A17" smd rect
			(at 4.19989 -5.100066)
			(size 0.381 1.3462)
			(layers "F.Cu" "F.Mask" "F.Paste")
			(net "P5V_STBY")
		)
		(pad "A18" smd rect
			(at 4.800092 -5.100066)
			(size 0.381 1.3462)
			(layers "F.Cu" "F.Mask" "F.Paste")
			(net "P5V_STBY")
		)
		(pad "A19" smd rect
			(at 5.40004 -5.100066)
			(size 0.381 1.3462)
			(layers "F.Cu" "F.Mask" "F.Paste")
			(net "GND")
		)
		(pad "B1" smd rect
			(at -5.40004 -7.450074)
			(size 0.381 1.3462)
			(layers "F.Cu" "F.Mask" "F.Paste")
			(net "GND")
		)
		(pad "B2" smd rect
			(at -4.800092 -7.450074)
			(size 0.381 1.3462)
			(layers "F.Cu" "F.Mask" "F.Paste")
			(net "USB2_DP")
		)
		(pad "B3" smd rect
			(at -4.19989 -7.450074)
			(size 0.381 1.3462)
			(layers "F.Cu" "F.Mask" "F.Paste")
			(net "USB2_DN")
		)
		(pad "B4" smd rect
			(at -3.599942 -7.450074)
			(size 0.381 1.3462)
			(layers "F.Cu" "F.Mask" "F.Paste")
			(net "GND")
		)
		(pad "B5" smd rect
			(at -2.999994 -7.450074)
			(size 0.381 1.3462)
			(layers "F.Cu" "F.Mask" "F.Paste")
			(net "FM_PFR_LED_AMBER_N")
		)
		(pad "B6" smd rect
			(at -2.400046 -7.450074)
			(size 0.381 1.3462)
			(layers "F.Cu" "F.Mask" "F.Paste")
			(net "FM_PFR_LED_BLUE_N")
		)
		(pad "B7" smd rect
			(at -1.800098 -7.450074)
			(size 0.381 1.3462)
			(layers "F.Cu" "F.Mask" "F.Paste")
			(net "GND")
		)
		(pad "B8" smd rect
			(at -1.199896 -7.450074)
			(size 0.381 1.3462)
			(layers "F.Cu" "F.Mask" "F.Paste")
			(net "RST_SMB_N")
		)
		(pad "B9" smd rect
			(at -0.599948 -7.450074)
			(size 0.381 1.3462)
			(layers "F.Cu" "F.Mask" "F.Paste")
			(net "PRSNT_DBV2_SLIMSAS")
		)
		(pad "B10" smd rect
			(at 0 -7.450074)
			(size 0.381 1.3462)
			(layers "F.Cu" "F.Mask" "F.Paste")
			(net "GND")
		)
		(pad "B11" smd rect
			(at 0.599948 -7.450074)
			(size 0.381 1.3462)
			(layers "F.Cu" "F.Mask" "F.Paste")
			(net "SMB_SWB_SCL")
		)
		(pad "B12" smd rect
			(at 1.199896 -7.450074)
			(size 0.381 1.3462)
			(layers "F.Cu" "F.Mask" "F.Paste")
			(net "SMB_SWB_SDA")
		)
		(pad "B13" smd rect
			(at 1.800098 -7.450074)
			(size 0.381 1.3462)
			(layers "F.Cu" "F.Mask" "F.Paste")
			(net "GND")
		)
		(pad "B14" smd rect
			(at 2.400046 -7.450074)
			(size 0.381 1.3462)
			(layers "F.Cu" "F.Mask" "F.Paste")
			(net "UART_DEBUG_TX")
		)
		(pad "B15" smd rect
			(at 2.999994 -7.450074)
			(size 0.381 1.3462)
			(layers "F.Cu" "F.Mask" "F.Paste")
			(net "UART_DEBUG_RX")
		)
		(pad "B16" smd rect
			(at 3.599942 -7.450074)
			(size 0.381 1.3462)
			(layers "F.Cu" "F.Mask" "F.Paste")
			(net "GND")
		)
		(pad "B17" smd rect
			(at 4.19989 -7.450074)
			(size 0.381 1.3462)
			(layers "F.Cu" "F.Mask" "F.Paste")
			(net "P3V3_STBY")
		)
		(pad "B18" smd rect
			(at 4.800092 -7.450074)
			(size 0.381 1.3462)
			(layers "F.Cu" "F.Mask" "F.Paste")
			(net "P5V_STBY")
		)
		(pad "B19" smd rect
			(at 5.40004 -7.450074)
			(size 0.381 1.3462)
			(layers "F.Cu" "F.Mask" "F.Paste")
			(net "GND")
		)
		(pad "G1" thru_hole circle
			(at 6.225032 5.750052)
			(size 1.0668 1.0668)
			(drill 0.6604)
			(layers "*.Cu" "*.Mask")
			(remove_unused_layers no)
			(net "GND")
			(clearance 0.0508)
			(thermal_gap 0.0508)
		)
		(pad "G2" thru_hole circle
			(at 6.225032 2.750058)
			(size 1.0668 1.0668)
			(drill 0.6604)
			(layers "*.Cu" "*.Mask")
			(remove_unused_layers no)
			(net "GND")
			(clearance 0.0508)
			(thermal_gap 0.0508)
		)
		(pad "G3" thru_hole circle
			(at -6.225032 2.750058)
			(size 1.0668 1.0668)
			(drill 0.6604)
			(layers "*.Cu" "*.Mask")
			(remove_unused_layers no)
			(net "GND")
			(clearance 0.0508)
			(thermal_gap 0.0508)
		)
		(pad "G4" thru_hole circle
			(at -6.225032 5.750052)
			(size 1.0668 1.0668)
			(drill 0.6604)
			(layers "*.Cu" "*.Mask")
			(remove_unused_layers no)
			(net "GND")
			(clearance 0.0508)
			(thermal_gap 0.0508)
		)
		(zone
			(layer "F.Cu")
			(hatch none 0.5)
			(connect_pads
				(clearance 0)
			)
			(min_thickness 0.25)
			(keepout
				(tracks not_allowed)
				(vias allowed)
				(pads allowed)
				(copperpour not_allowed)
				(footprints allowed)
			)
			(placement
				(enabled no)
				(sheetname "")
			)
			(fill
				(thermal_gap 0.5)
				(thermal_bridge_width 0.5)
				(island_removal_mode 0)
			)
			(polygon
				(pts
					(xy 16.12519 -85.149944) (xy 16.12519 -83.584288) (xy 15.125192 -83.584288) (xy 15.125192 -85.149944)
				)
			)
		)
		(zone
			(layer "F.Cu")
			(hatch none 0.5)
			(connect_pads
				(clearance 0)
			)
			(min_thickness 0.25)
			(keepout
				(tracks not_allowed)
				(vias allowed)
				(pads allowed)
				(copperpour not_allowed)
				(footprints allowed)
			)
			(placement
				(enabled no)
				(sheetname "")
			)
			(fill
				(thermal_gap 0.5)
				(thermal_bridge_width 0.5)
				(island_removal_mode 0)
			)
			(polygon
				(pts
					(xy 16.12519 -82.415888) (xy 16.12519 -80.587088) (xy 15.125192 -80.587088) (xy 15.125192 -82.415888)
				)
			)
		)
		(zone
			(layer "F.Cu")
			(hatch none 0.5)
			(connect_pads
				(clearance 0)
			)
			(min_thickness 0.25)
			(keepout
				(tracks not_allowed)
				(vias allowed)
				(pads allowed)
				(copperpour not_allowed)
				(footprints allowed)
			)
			(placement
				(enabled no)
				(sheetname "")
			)
			(fill
				(thermal_gap 0.5)
				(thermal_bridge_width 0.5)
				(island_removal_mode 0)
			)
			(polygon
				(pts
					(xy 28.575 -85.149944) (xy 28.575 -83.584288) (xy 27.575002 -83.584288) (xy 27.575002 -85.149944)
				)
			)
		)
		(zone
			(layer "F.Cu")
			(hatch none 0.5)
			(connect_pads
				(clearance 0)
			)
			(min_thickness 0.25)
			(keepout
				(tracks not_allowed)
				(vias allowed)
				(pads allowed)
				(copperpour not_allowed)
				(footprints allowed)
			)
			(placement
				(enabled no)
				(sheetname "")
			)
			(fill
				(thermal_gap 0.5)
				(thermal_bridge_width 0.5)
				(island_removal_mode 0)
			)
			(polygon
				(pts
					(xy 28.575 -82.415888) (xy 28.575 -80.587088) (xy 27.575002 -80.587088) (xy 27.575002 -82.415888)
				)
			)
		)
		(zone
			(layer "F.Cu")
			(hatch none 0.5)
			(connect_pads
				(clearance 0)
			)
			(min_thickness 0.25)
			(keepout
				(tracks not_allowed)
				(vias allowed)
				(pads allowed)
				(copperpour not_allowed)
				(footprints allowed)
			)
			(placement
				(enabled no)
				(sheetname "")
			)
			(fill
				(thermal_gap 0.5)
				(thermal_bridge_width 0.5)
				(island_removal_mode 0)
			)
			(polygon
				(pts
					(xy 17.524984 -79.44993) (xy 17.524984 -76.05014) (xy 15.125192 -76.05014) (xy 15.125192 -79.44993)
					(xy 15.423896 -79.44993) (xy 15.423896 -79.409036) (xy 15.830296 -79.409036) (xy 15.830296 -79.44993)
				)
			)
		)
		(zone
			(layer "F.Cu")
			(hatch none 0.5)
			(connect_pads
				(clearance 0)
			)
			(min_thickness 0.25)
			(keepout
				(tracks not_allowed)
				(vias allowed)
				(pads allowed)
				(copperpour not_allowed)
				(footprints allowed)
			)
			(placement
				(enabled no)
				(sheetname "")
			)
			(fill
				(thermal_gap 0.5)
				(thermal_bridge_width 0.5)
				(island_removal_mode 0)
			)
			(polygon
				(pts
					(xy 26.175208 -79.44993) (xy 26.175208 -76.05014) (xy 28.575 -76.05014) (xy 28.575 -79.44993) (xy 28.276296 -79.44993)
					(xy 28.276296 -79.409036) (xy 27.869896 -79.409036) (xy 27.869896 -79.44993)
				)
			)
		)
		(zone
			(layers "F.Cu" "B.Cu" "In1.Cu" "In2.Cu")
			(hatch none 0.5)
			(connect_pads
				(clearance 0)
			)
			(min_thickness 0.25)
			(keepout
				(tracks not_allowed)
				(vias allowed)
				(pads allowed)
				(copperpour not_allowed)
				(footprints allowed)
			)
			(placement
				(enabled no)
				(sheetname "")
			)
			(fill
				(thermal_gap 0.5)
				(thermal_bridge_width 0.5)
				(island_removal_mode 0)
			)
			(polygon
				(pts
					(arc
						(start 17.392142 -74.84999)
						(mid 15.20825 -74.84999)
						(end 17.392142 -74.84999)
					)
				)
			)
		)
		(zone
			(layers "F.Cu" "B.Cu" "In1.Cu" "In2.Cu")
			(hatch none 0.5)
			(connect_pads
				(clearance 0)
			)
			(min_thickness 0.25)
			(keepout
				(tracks not_allowed)
				(vias allowed)
				(pads allowed)
				(copperpour not_allowed)
				(footprints allowed)
			)
			(placement
				(enabled no)
				(sheetname "")
			)
			(fill
				(thermal_gap 0.5)
				(thermal_bridge_width 0.5)
				(island_removal_mode 0)
			)
			(polygon
				(pts
					(arc
						(start 28.49245 -74.84999)
						(mid 26.307542 -74.84999)
						(end 28.49245 -74.84999)
					)
				)
			)
		)
	)
	(footprint ""
		(layer "F.Cu")
		(at 88.146382 -62.918086 180)
		(property "Reference" "J3"
			(at 2.548382 2.079244 0)
			(unlocked yes)
			(layer "F.SilkS")
			(effects
				(font
					(size 0.7874 0.5842)
					(thickness 0.1524)
				)
				(justify left)
			)
		)
		(property "Value" ""
			(at 0 0 180)
			(layer "F.Fab")
			(effects
				(font
					(size 1.27 1.27)
				)
			)
		)
		(duplicate_pad_numbers_are_jumpers no)
		(fp_line
			(start 3.330702 -4.771136)
			(end 0 4.011168)
			(stroke
				(width 0.1524)
				(type default)
			)
			(layer "F.SilkS")
		)
		(fp_line
			(start 0 4.011168)
			(end -3.330702 -4.771136)
			(stroke
				(width 0.1524)
				(type default)
			)
			(layer "F.SilkS")
		)
		(fp_line
			(start -3.330702 -4.771136)
			(end 3.330702 -4.771136)
			(stroke
				(width 0.1524)
				(type default)
			)
			(layer "F.SilkS")
		)
		(fp_line
			(start 3.330702 -4.771136)
			(end 0 4.011168)
			(stroke
				(width 0.1)
				(type default)
			)
			(layer "F.Fab")
		)
		(fp_line
			(start 0 4.011168)
			(end -3.330702 -4.771136)
			(stroke
				(width 0.1)
				(type default)
			)
			(layer "F.Fab")
		)
		(fp_line
			(start -3.330702 -4.771136)
			(end 3.330702 -4.771136)
			(stroke
				(width 0.1)
				(type default)
			)
			(layer "F.Fab")
		)
		(pad "1" thru_hole circle
			(at 0 0 180)
			(size 2.159 2.159)
			(drill 1.7018)
			(layers "*.Cu" "*.Mask")
			(remove_unused_layers no)
			(net "GND_TDR")
			(clearance 0.0254)
			(thermal_gap 0.0254)
		)
		(pad "2" thru_hole circle
			(at -1.27 -3.348736 180)
			(size 2.159 2.159)
			(drill 1.7018)
			(layers "*.Cu" "*.Mask")
			(remove_unused_layers no)
			(net "TDR_SE_50_OHM_TOP")
			(clearance 0.0254)
			(thermal_gap 0.0254)
		)
		(pad "3" thru_hole circle
			(at 1.27 -3.348736 180)
			(size 2.159 2.159)
			(drill 1.7018)
			(layers "*.Cu" "*.Mask")
			(remove_unused_layers no)
			(net "TDR_SE_50_OHM_TOP")
			(clearance 0.0254)
			(thermal_gap 0.0254)
		)
	)
)
